(kicad_pcb
	(version 20260206)
	(generator "pcbnew")
	(generator_version "10.0")
	(general
		(thickness 1.6)
		(legacy_teardrops no)
	)
	(paper "A4")
	(title_block
		(title "Bryce Canyon_SCC_16316-1_OCP.brd")
		(comment 1 "Bryce Canyon / footprints 578-581 of 1561")
	)
	(layers
		(0 "F.Cu" signal "TOP")
		(4 "In1.Cu" signal "L2GND")
		(6 "In2.Cu" signal "L3")
		(8 "In3.Cu" signal "L4VCC")
		(10 "In4.Cu" signal "L5VCC")
		(12 "In5.Cu" signal "L6")
		(14 "In6.Cu" signal "L7GND")
		(2 "B.Cu" signal "BOTTOM")
		(9 "F.Adhes" user "F.Adhesive")
		(11 "B.Adhes" user "B.Adhesive")
		(13 "F.Paste" user "Package Geometry/Pastemask Top")
		(15 "B.Paste" user "Package Geometry/Pastemask Bottom")
		(5 "F.SilkS" user "Ref Des/Silkscreen Top")
		(7 "B.SilkS" user "Ref Des/Silkscreen Bottom")
		(1 "F.Mask" user "Board Geometry/Soldermask Top")
		(3 "B.Mask" user "Board Geometry/Soldermask Bottom")
		(17 "Dwgs.User" user "User.Drawings")
		(19 "Cmts.User" user "User.Comments")
		(21 "Eco1.User" user "User.Eco1")
		(23 "Eco2.User" user "User.Eco2")
		(25 "Edge.Cuts" user "Board Geometry/Outline")
		(27 "Margin" user)
		(31 "F.CrtYd" user "Package Geometry/Place Bound Top")
		(29 "B.CrtYd" user "Package Geometry/Place Bound Bottom")
		(35 "F.Fab" user "Ref Des/Assembly Top")
		(33 "B.Fab" user "Ref Des/Assembly Bottom")
	)
	(footprint ""
		(layer "F.Cu")
		(at 108.6358 -86.9442 180)
		(property "Reference" "R120"
			(at 0 0 180)
			(layer "F.SilkS")
			(hide yes)
			(effects
				(font
					(size 1.27 1.27)
				)
			)
		)
		(property "Value" "10KR2F-2-GP"
			(at 0.064008 -3.993896 180)
			(unlocked yes)
			(layer "F.Fab")
			(hide yes)
			(effects
				(font
					(size 1.016 1.016)
					(thickness 0.1524)
				)
			)
		)
		(property "Device Type" "R402H16"
			(at 0.064008 -5.517896 180)
			(unlocked yes)
			(layer "F.Fab")
			(hide yes)
			(effects
				(font
					(size 1.016 1.016)
					(thickness 0.1524)
				)
			)
		)
		(duplicate_pad_numbers_are_jumpers no)
		(fp_line
			(start 0.508 -0.9398)
			(end -0.508 -0.9398)
			(stroke
				(width 0.1524)
				(type default)
			)
			(layer "F.SilkS")
		)
		(fp_line
			(start -0.508 -0.9398)
			(end -0.508 0.9398)
			(stroke
				(width 0.1524)
				(type default)
			)
			(layer "F.SilkS")
		)
		(fp_rect
			(start -0.508 0.9398)
			(end 0.508 -0.9398)
			(stroke
				(width 0)
				(type default)
			)
			(fill no)
			(layer "F.CrtYd")
		)
		(fp_rect
			(start -0.508 0.9398)
			(end 0.508 -0.9398)
			(stroke
				(width 0)
				(type default)
			)
			(fill no)
			(layer "F.Fab")
		)
		(pad "1" smd custom
			(at 0 -0.4445 180)
			(size 0.1397 0.1397)
			(layers "F.Cu" "F.Mask" "F.Paste")
			(net "SOFT_RESET_N")
			(options
				(clearance outline)
				(anchor circle)
			)
			(primitives
				(gr_poly
					(pts
						(arc
							(start -0.1778 -0.2794)
							(mid -0.249642 -0.249642)
							(end -0.2794 -0.1778)
						)
						(arc
							(start -0.2794 0.1778)
							(mid -0.249642 0.249642)
							(end -0.1778 0.2794)
						)
						(arc
							(start 0.1778 0.2794)
							(mid 0.249642 0.249642)
							(end 0.2794 0.1778)
						)
						(arc
							(start 0.2794 -0.1778)
							(mid 0.249642 -0.249642)
							(end 0.1778 -0.2794)
						)
					)
					(width 0)
					(fill yes)
				)
			)
		)
		(pad "2" smd custom
			(at 0 0.4445 180)
			(size 0.1397 0.1397)
			(layers "F.Cu" "F.Mask" "F.Paste")
			(net "P1V8_E")
			(options
				(clearance outline)
				(anchor circle)
			)
			(primitives
				(gr_poly
					(pts
						(arc
							(start -0.1778 -0.2794)
							(mid -0.249642 -0.249642)
							(end -0.2794 -0.1778)
						)
						(arc
							(start -0.2794 0.1778)
							(mid -0.249642 0.249642)
							(end -0.1778 0.2794)
						)
						(arc
							(start 0.1778 0.2794)
							(mid 0.249642 0.249642)
							(end 0.2794 0.1778)
						)
						(arc
							(start 0.2794 -0.1778)
							(mid 0.249642 -0.249642)
							(end 0.1778 -0.2794)
						)
					)
					(width 0)
					(fill yes)
				)
			)
		)
	)
	(footprint ""
		(layer "F.Cu")
		(at 19.4564 -32.3342 180)
		(property "Reference" "D37"
			(at 0 0 180)
			(layer "F.SilkS")
			(hide yes)
			(effects
				(font
					(size 1.27 1.27)
				)
			)
		)
		(property "Value" "SMF15A-GP"
			(at -2.0955 1.2192 180)
			(unlocked yes)
			(layer "F.Fab")
			(hide yes)
			(effects
				(font
					(size 1.016 1.016)
					(thickness 0.1524)
				)
			)
		)
		(property "Device Type" "SOD123AK-2H43"
			(at -2.0955 -0.3048 180)
			(unlocked yes)
			(layer "F.Fab")
			(hide yes)
			(effects
				(font
					(size 1.016 1.016)
					(thickness 0.1524)
				)
			)
		)
		(duplicate_pad_numbers_are_jumpers no)
		(fp_line
			(start 1.1557 2.921)
			(end -1.1557 2.921)
			(stroke
				(width 0.508)
				(type default)
			)
			(layer "F.SilkS")
		)
		(fp_line
			(start 1.1557 2.7686)
			(end 1.1557 -2.7686)
			(stroke
				(width 0.1524)
				(type default)
			)
			(layer "F.SilkS")
		)
		(fp_line
			(start 1.1557 -2.7686)
			(end -1.1557 -2.7686)
			(stroke
				(width 0.1524)
				(type default)
			)
			(layer "F.SilkS")
		)
		(fp_line
			(start -1.1557 2.7686)
			(end 1.1557 2.7686)
			(stroke
				(width 0.1524)
				(type default)
			)
			(layer "F.SilkS")
		)
		(fp_line
			(start -1.1557 -2.7686)
			(end -1.1557 2.7686)
			(stroke
				(width 0.1524)
				(type default)
			)
			(layer "F.SilkS")
		)
		(fp_poly
			(pts
				(xy -0.4572 1.8669) (xy -0.4572 1.397) (xy -0.9017 1.397) (xy -0.9017 -1.397) (xy -0.4572 -1.397)
				(xy -0.4572 -1.8669) (xy 0.4572 -1.8669) (xy 0.4572 -1.397) (xy 0.9017 -1.397) (xy 0.9017 1.397)
				(xy 0.4572 1.397) (xy 0.4572 1.8669)
			)
			(stroke
				(width 0)
				(type default)
			)
			(fill no)
			(layer "F.CrtYd")
		)
		(fp_poly
			(pts
				(xy -1.4097 2.8448) (xy -1.4097 -2.8448) (xy 1.4097 -2.8448) (xy 1.4097 1.3716) (xy 0.9017 1.3716)
				(xy 0.9017 -1.397) (xy 0.4572 -1.397) (xy 0.4572 -1.8669) (xy -0.4572 -1.8669) (xy -0.4572 -1.397)
				(xy -0.9017 -1.397) (xy -0.9017 1.397) (xy -0.4572 1.397) (xy -0.4572 1.8669) (xy 0.4572 1.8669)
				(xy 0.4572 1.397) (xy 0.9017 1.397) (xy 0.9017 1.3843) (xy 1.4097 1.3843) (xy 1.4097 2.8448)
			)
			(stroke
				(width 0)
				(type default)
			)
			(fill no)
			(layer "F.CrtYd")
		)
		(fp_rect
			(start -1.4097 2.8448)
			(end 1.4097 -2.8448)
			(stroke
				(width 0)
				(type default)
			)
			(fill no)
			(layer "F.Fab")
		)
		(pad "A" smd rect
			(at 0 -1.75768 180)
			(size 1.143 1.4986)
			(layers "F.Cu" "F.Mask" "F.Paste")
			(net "GND")
		)
		(pad "K" smd rect
			(at 0 1.75768 180)
			(size 1.143 1.4986)
			(layers "F.Cu" "F.Mask" "F.Paste")
			(net "P12V_MAIN")
		)
	)
	(footprint ""
		(layer "F.Cu")
		(at 12.8778 -85.7504 -90)
		(property "Reference" "C558"
			(at 0 0 270)
			(layer "F.SilkS")
			(hide yes)
			(effects
				(font
					(size 1.27 1.27)
				)
			)
		)
		(property "Value" "SCD1U16V2KX-3GP"
			(at 1.1811 -2.7051 270)
			(unlocked yes)
			(layer "F.Fab")
			(hide yes)
			(effects
				(font
					(size 1.016 1.016)
					(thickness 0.1524)
				)
			)
		)
		(property "Device Type" "C402H22"
			(at 1.1811 -4.2291 270)
			(unlocked yes)
			(layer "F.Fab")
			(hide yes)
			(effects
				(font
					(size 1.016 1.016)
					(thickness 0.1524)
				)
			)
		)
		(duplicate_pad_numbers_are_jumpers no)
		(fp_rect
			(start -0.4318 0.9525)
			(end 0.4318 -0.9525)
			(stroke
				(width 0)
				(type default)
			)
			(fill no)
			(layer "F.CrtYd")
		)
		(fp_rect
			(start -0.4318 0.9525)
			(end 0.4318 -0.9525)
			(stroke
				(width 0)
				(type default)
			)
			(fill no)
			(layer "F.Fab")
		)
		(pad "1" smd custom
			(at 0 -0.4445 270)
			(size 0.1524 0.1524)
			(layers "F.Cu" "F.Mask" "F.Paste")
			(net "P1V8_E")
			(options
				(clearance outline)
				(anchor circle)
			)
			(primitives
				(gr_poly
					(pts
						(arc
							(start 0.3048 -0.2032)
							(mid 0.275042 -0.275042)
							(end 0.2032 -0.3048)
						)
						(arc
							(start -0.2032 -0.3048)
							(mid -0.275042 -0.275042)
							(end -0.3048 -0.2032)
						)
						(arc
							(start -0.3048 0.2032)
							(mid -0.275042 0.275042)
							(end -0.2032 0.3048)
						)
						(arc
							(start 0.2032 0.3048)
							(mid 0.275042 0.275042)
							(end 0.3048 0.2032)
						)
					)
					(width 0)
					(fill yes)
				)
			)
		)
		(pad "2" smd custom
			(at 0 0.4445 270)
			(size 0.1524 0.1524)
			(layers "F.Cu" "F.Mask" "F.Paste")
			(net "GND")
			(options
				(clearance outline)
				(anchor circle)
			)
			(primitives
				(gr_poly
					(pts
						(arc
							(start 0.3048 -0.2032)
							(mid 0.275042 -0.275042)
							(end 0.2032 -0.3048)
						)
						(arc
							(start -0.2032 -0.3048)
							(mid -0.275042 -0.275042)
							(end -0.3048 -0.2032)
						)
						(arc
							(start -0.3048 0.2032)
							(mid -0.275042 0.275042)
							(end -0.2032 0.3048)
						)
						(arc
							(start 0.2032 0.3048)
							(mid 0.275042 0.275042)
							(end 0.3048 0.2032)
						)
					)
					(width 0)
					(fill yes)
				)
			)
		)
	)
	(footprint ""
		(layer "F.Cu")
		(at 29.99994 -120.000014 180)
		(property "Reference" "DB1"
			(at 0 0 180)
			(layer "F.SilkS")
			(hide yes)
			(effects
				(font
					(size 1.27 1.27)
				)
			)
		)
		(property "Value" "JWT-CONN14A-GP"
			(at 7.4549 -7.2898 180)
			(unlocked yes)
			(layer "F.Fab")
			(hide yes)
			(effects
				(font
					(size 1.016 1.016)
					(thickness 0.1524)
				)
			)
		)
		(property "Device Type" "A2005WR0-2CX7PBS"
			(at 7.4549 -8.8138 180)
			(unlocked yes)
			(layer "F.Fab")
			(hide yes)
			(effects
				(font
					(size 1.016 1.016)
					(thickness 0.1524)
				)
			)
		)
		(duplicate_pad_numbers_are_jumpers no)
		(fp_line
			(start 8.5852 3.7592)
			(end 8.5852 -3.7592)
			(stroke
				(width 0.1524)
				(type default)
			)
			(layer "F.SilkS")
		)
		(fp_line
			(start 8.5852 -1.016)
			(end 8.128 -1.016)
			(stroke
				(width 0.1524)
				(type default)
			)
			(layer "F.SilkS")
		)
		(fp_line
			(start 8.5852 -3.7592)
			(end -8.5852 -3.7592)
			(stroke
				(width 0.1524)
				(type default)
			)
			(layer "F.SilkS")
		)
		(fp_line
			(start 8.128 0)
			(end 8.5852 0)
			(stroke
				(width 0.1524)
				(type default)
			)
			(layer "F.SilkS")
		)
		(fp_line
			(start 8.128 -1.016)
			(end 8.128 0)
			(stroke
				(width 0.1524)
				(type default)
			)
			(layer "F.SilkS")
		)
		(fp_line
			(start -5.8039 3.8608)
			(end -6.1849 3.8608)
			(stroke
				(width 0.3302)
				(type default)
			)
			(layer "F.SilkS")
		)
		(fp_line
			(start -8.128 0)
			(end -8.5852 0)
			(stroke
				(width 0.1524)
				(type default)
			)
			(layer "F.SilkS")
		)
		(fp_line
			(start -8.128 -1.016)
			(end -8.128 0)
			(stroke
				(width 0.1524)
				(type default)
			)
			(layer "F.SilkS")
		)
		(fp_line
			(start -8.5852 3.7592)
			(end 8.5852 3.7592)
			(stroke
				(width 0.1524)
				(type default)
			)
			(layer "F.SilkS")
		)
		(fp_line
			(start -8.5852 -1.016)
			(end -8.128 -1.016)
			(stroke
				(width 0.1524)
				(type default)
			)
			(layer "F.SilkS")
		)
		(fp_line
			(start -8.5852 -3.7592)
			(end -8.5852 3.7592)
			(stroke
				(width 0.1524)
				(type default)
			)
			(layer "F.SilkS")
		)
		(fp_poly
			(pts
				(xy -5.987288 3.81) (xy -6.495288 4.318) (xy -5.479288 4.318)
			)
			(stroke
				(width 0)
				(type default)
			)
			(fill yes)
			(layer "F.SilkS")
		)
		(fp_poly
			(pts
				(xy -4.16179 0.550164) (xy 4.161028 0.550164) (xy 4.161028 -0.550164) (xy -4.16179 -0.550164)
			)
			(stroke
				(width 0)
				(type default)
			)
			(fill yes)
			(layer "F.SilkS")
		)
		(fp_rect
			(start -8.3312 2.9972)
			(end 8.3312 -2.9972)
			(stroke
				(width 0)
				(type default)
			)
			(fill no)
			(layer "F.CrtYd")
		)
		(fp_poly
			(pts
				(xy 8.8392 -2.9972) (xy -8.3312 -2.9972) (xy -8.3312 2.9972) (xy 8.3312 2.9972) (xy 8.3312 -2.9845)
				(xy 8.8392 -2.9845) (xy 8.8392 4.0132) (xy -8.8392 4.0132) (xy -8.8392 -4.0132) (xy 8.8392 -4.0132)
			)
			(stroke
				(width 0)
				(type default)
			)
			(fill no)
			(layer "F.CrtYd")
		)
		(fp_rect
			(start -8.8392 4.0132)
			(end 8.8392 -4.0132)
			(stroke
				(width 0)
				(type default)
			)
			(fill no)
			(layer "F.Fab")
		)
		(pad "" np_thru_hole circle
			(at -4.99999 0 180)
			(size 0.254 0.254)
			(drill 1.0668)
			(layers "*.Cu" "*.Mask")
			(clearance 0.762)
			(thermal_gap 0.762)
		)
		(pad "" np_thru_hole circle
			(at 4.99999 0 180)
			(size 0.254 0.254)
			(drill 1.0668)
			(layers "*.Cu" "*.Mask")
			(clearance 0.762)
			(thermal_gap 0.762)
		)
		(pad "1" smd rect
			(at -5.999988 2.124964 180)
			(size 0.9906 2.7432)
			(layers "F.Cu" "F.Mask" "F.Paste")
			(net "DEBUG_LOW_HEX_0")
		)
		(pad "2" smd rect
			(at -5.999988 -2.124964 180)
			(size 0.9906 2.7432)
			(layers "F.Cu" "F.Mask" "F.Paste")
			(net "DEBUG_LOW_HEX_1")
		)
		(pad "3" smd rect
			(at -3.999992 2.124964 180)
			(size 0.9906 2.7432)
			(layers "F.Cu" "F.Mask" "F.Paste")
			(net "DEBUG_LOW_HEX_2")
		)
		(pad "4" smd rect
			(at -3.999992 -2.124964 180)
			(size 0.9906 2.7432)
			(layers "F.Cu" "F.Mask" "F.Paste")
			(net "DEBUG_LOW_HEX_3")
		)
		(pad "5" smd rect
			(at -1.999996 2.124964 180)
			(size 0.9906 2.7432)
			(layers "F.Cu" "F.Mask" "F.Paste")
			(net "DEBUG_HIGH_HEX_0")
		)
		(pad "6" smd rect
			(at -1.999996 -2.124964 180)
			(size 0.9906 2.7432)
			(layers "F.Cu" "F.Mask" "F.Paste")
			(net "DEBUG_HIGH_HEX_1")
		)
		(pad "7" smd rect
			(at 0 2.124964 180)
			(size 0.9906 2.7432)
			(layers "F.Cu" "F.Mask" "F.Paste")
			(net "DEBUG_HIGH_HEX_2")
		)
		(pad "8" smd rect
			(at 0 -2.124964 180)
			(size 0.9906 2.7432)
			(layers "F.Cu" "F.Mask" "F.Paste")
			(net "DEBUG_HIGH_HEX_3")
		)
		(pad "9" smd rect
			(at 1.999996 2.124964 180)
			(size 0.9906 2.7432)
			(layers "F.Cu" "F.Mask" "F.Paste")
			(net "Net_66")
		)
		(pad "10" smd rect
			(at 1.999996 -2.124964 180)
			(size 0.9906 2.7432)
			(layers "F.Cu" "F.Mask" "F.Paste")
			(net "Net_65")
		)
		(pad "11" smd rect
			(at 3.999992 2.124964 180)
			(size 0.9906 2.7432)
			(layers "F.Cu" "F.Mask" "F.Paste")
			(net "Net_64")
		)
		(pad "12" smd rect
			(at 3.999992 -2.124964 180)
			(size 0.9906 2.7432)
			(layers "F.Cu" "F.Mask" "F.Paste")
			(net "Net_63")
		)
		(pad "13" smd rect
			(at 5.999988 2.124964 180)
			(size 0.9906 2.7432)
			(layers "F.Cu" "F.Mask" "F.Paste")
			(net "GND")
		)
		(pad "14" smd rect
			(at 5.999988 -2.124964 180)
			(size 0.9906 2.7432)
			(layers "F.Cu" "F.Mask" "F.Paste")
			(net "P5V")
		)
		(zone
			(layer "F.Cu")
			(hatch none 0.5)
			(connect_pads
				(clearance 0)
			)
			(min_thickness 0.25)
			(keepout
				(tracks not_allowed)
				(vias allowed)
				(pads allowed)
				(copperpour not_allowed)
				(footprints allowed)
			)
			(placement
				(enabled no)
				(sheetname "")
			)
			(fill
				(thermal_gap 0.5)
				(thermal_bridge_width 0.5)
				(island_removal_mode 0)
			)
			(polygon
				(pts
					(xy 36.495228 -120.753378) (xy 23.504652 -120.753378) (xy 23.504652 -119.24665) (xy 36.495228 -119.24665)
				)
			)
		)
		(zone
			(layer "F.Cu")
			(hatch none 0.5)
			(connect_pads
				(clearance 0)
			)
			(min_thickness 0.25)
			(keepout
				(tracks allowed)
				(vias not_allowed)
				(pads allowed)
				(copperpour not_allowed)
				(footprints allowed)
			)
			(placement
				(enabled no)
				(sheetname "")
			)
			(fill
				(thermal_gap 0.5)
				(thermal_bridge_width 0.5)
				(island_removal_mode 0)
			)
			(polygon
				(pts
					(xy 36.495228 -120.753378) (xy 23.504652 -120.753378) (xy 23.504652 -119.24665) (xy 36.495228 -119.24665)
				)
			)
		)
		(zone
			(layer "F.Cu")
			(hatch none 0.5)
			(connect_pads
				(clearance 0)
			)
			(min_thickness 0.25)
			(keepout
				(tracks allowed)
				(vias not_allowed)
				(pads allowed)
				(copperpour not_allowed)
				(footprints allowed)
			)
			(placement
				(enabled no)
				(sheetname "")
			)
			(fill
				(thermal_gap 0.5)
				(thermal_bridge_width 0.5)
				(island_removal_mode 0)
			)
			(polygon
				(pts
					(xy 36.495228 -120.245378) (xy 36.495228 -120.753378) (xy 23.504652 -120.753378) (xy 23.504906 -120.245378)
				)
			)
		)
		(zone
			(layer "F.Cu")
			(hatch none 0.5)
			(connect_pads
				(clearance 0)
			)
			(min_thickness 0.25)
			(keepout
				(tracks allowed)
				(vias not_allowed)
				(pads allowed)
				(copperpour not_allowed)
				(footprints allowed)
			)
			(placement
				(enabled no)
				(sheetname "")
			)
			(fill
				(thermal_gap 0.5)
				(thermal_bridge_width 0.5)
				(island_removal_mode 0)
			)
			(polygon
				(pts
					(xy 36.495228 -119.24665) (xy 36.495228 -119.75465) (xy 23.504652 -119.75465) (xy 23.504652 -119.24665)
				)
			)
		)
		(zone
			(layers "F.Cu" "B.Cu" "In1.Cu" "In2.Cu" "In3.Cu" "In4.Cu" "In5.Cu" "In6.Cu")
			(hatch none 0.5)
			(connect_pads
				(clearance 0)
			)
			(min_thickness 0.25)
			(keepout
				(tracks not_allowed)
				(vias allowed)
				(pads allowed)
				(copperpour not_allowed)
				(footprints allowed)
			)
			(placement
				(enabled no)
				(sheetname "")
			)
			(fill
				(thermal_gap 0.5)
				(thermal_bridge_width 0.5)
				(island_removal_mode 0)
			)
			(polygon
				(pts
					(arc
						(start 25.83815 -120.000014)
						(mid 24.16175 -120.000014)
						(end 25.83815 -120.000014)
					)
				)
			)
		)
		(zone
			(layers "F.Cu" "B.Cu" "In1.Cu" "In2.Cu" "In3.Cu" "In4.Cu" "In5.Cu" "In6.Cu")
			(hatch none 0.5)
			(connect_pads
				(clearance 0)
			)
			(min_thickness 0.25)
			(keepout
				(tracks not_allowed)
				(vias allowed)
				(pads allowed)
				(copperpour not_allowed)
				(footprints allowed)
			)
			(placement
				(enabled no)
				(sheetname "")
			)
			(fill
				(thermal_gap 0.5)
				(thermal_bridge_width 0.5)
				(island_removal_mode 0)
			)
			(polygon
				(pts
					(arc
						(start 35.83813 -120.000014)
						(mid 34.16173 -120.000014)
						(end 35.83813 -120.000014)
					)
				)
			)
		)
	)
)
